# Stackup_F0T_Management_Board_12L_1p6mm_IT-170GRA1_RG311_Rev0p2_20220715 的複本.xls — Information (pcb-stackup)
| Stackup Information : |  |  |  |  |  |  |  |
| Stackup Type |  |  | Single Material |  |  |  |  |
| Project Name |  |  | F0T |  |  |  |  |
| Board Class |  |  | Management_Board |  |  |  |  |
| Number of Layers |  |  | 12 |  |  |  |  |
| PCB Material |  |  | IT-170GRA1 |  |  |  |  |
| Copper Foil |  |  | RG311 (Roughness < 2.5um) |  |  |  |  |
| PCB Thickness (mm) |  |  | 1.6 |  |  |  |  |
| PCB Thickness (mil) |  |  | 63 |  |  |  |  |
| Aspect Ratio |  |  | 6.43 |  |  |  |  |
| Last Update |  |  | 44757 |  |  |  |  |
| Revision |  |  | 0.2 |  |  |  |  |
| Creator |  |  | Allen |  |  |  |  |
| Loss Requirement Table : |  |  |  |  |  |  |  |
| SDD21 @ Freq(GHz) |  | 4 | 4 | 4 | 4 | 4 | 4 |
| Requirement (db/inch) | Layer | TOP | IN1 | IN2 | IN3 | IN4 | BOTTOM |
|  | Loss | 0.69 | 0.65 | 0.65 | 0.65 | 0.65 | 0.69 |
| SDD21 @ Freq(GHz) |  | 8 | 8 | 8 | 8 | 8 | 8 |
| Requirement (db/inch) | Layer | TOP | IN1 | IN2 | IN3 | IN4 | BOTTOM |
|  | Loss | 1.27 | 1.16 | 1.16 | 1.16 | 1.16 | 1.27 |
| Stackup History : |  |  |  |  |  |  |  |
| Date (yyyy/mm/dd) | Revision | Notes |  |  |  |  |  |
| 44509 | 0.1 | First release |  |  |  |  |  |
| 44757 | 0.2 | Add VIPPO processing based on Meta request, please refer to Mail "Re_ _External_  FW_ Meta_Quanta via half-plugging discussion.msg" |  |  |  |  |  |
